(kicad_pcb
	(version 20260206)
	(generator "pcbnew")
	(generator_version "10.0")
	(general
		(thickness 1.6)
		(legacy_teardrops no)
	)
	(paper "A4")
	(title_block
		(title "Wiwynn_Tioga_Pass_MB.brd")
		(comment 1 "Tioga Pass / footprint 3114 of 4770 (J9U1), pads 244-291 of 291")
	)
	(layers
		(0 "F.Cu" signal "TOP")
		(4 "In1.Cu" signal "L2GND")
		(6 "In2.Cu" signal "L3")
		(8 "In3.Cu" signal "L4GND")
		(10 "In4.Cu" signal "L5")
		(12 "In5.Cu" signal "L6GND")
		(14 "In6.Cu" signal "L7VCC")
		(16 "In7.Cu" signal "L8VCC")
		(18 "In8.Cu" signal "L9GND")
		(20 "In9.Cu" signal "L10")
		(22 "In10.Cu" signal "L11GND")
		(24 "In11.Cu" signal "L12")
		(26 "In12.Cu" signal "L13GND")
		(2 "B.Cu" signal "BOTTOM")
		(9 "F.Adhes" user "F.Adhesive")
		(11 "B.Adhes" user "B.Adhesive")
		(13 "F.Paste" user "Package Geometry/Pastemask Top")
		(15 "B.Paste" user "Package Geometry/Pastemask Bottom")
		(5 "F.SilkS" user "Ref Des/Silkscreen Top")
		(7 "B.SilkS" user "Ref Des/Silkscreen Bottom")
		(1 "F.Mask" user "Board Geometry/Soldermask Top")
		(3 "B.Mask" user "Board Geometry/Soldermask Bottom")
		(17 "Dwgs.User" user "User.Drawings")
		(19 "Cmts.User" user "User.Comments")
		(21 "Eco1.User" user "User.Eco1")
		(23 "Eco2.User" user "User.Eco2")
		(25 "Edge.Cuts" user "Board Geometry/Outline")
		(27 "Margin" user)
		(31 "F.CrtYd" user "Package Geometry/Place Bound Top")
		(29 "B.CrtYd" user "Package Geometry/Place Bound Bottom")
		(35 "F.Fab" user "Ref Des/Assembly Top")
		(33 "B.Fab" user "Ref Des/Assembly Bottom")
	)
	(footprint ""
		(layer "B.Cu")
		(at 29.699458 -15.222982 90)
		(property "Reference" "J9U1"
			(at 2.276348 37.991542 0)
			(unlocked yes)
			(layer "B.SilkS")
			(effects
				(font
					(size 0.7874 0.5842)
					(thickness 0.1524)
				)
				(justify left mirror)
			)
		)
		(property "Value" ""
			(at 0 0 90)
			(layer "B.Fab")
			(effects
				(font
					(size 1.27 1.27)
				)
				(justify mirror)
			)
		)
		(duplicate_pad_numbers_are_jumpers no)
		(pad "241" smd rect
			(at -4.59994 86.700106 270)
			(size 1.8034 0.508)
			(layers "B.Cu" "B.Mask" "B.Paste")
			(net "GND")
		)
		(pad "242" smd rect
			(at -4.59994 87.54999 270)
			(size 1.8034 0.508)
			(layers "B.Cu" "B.Mask" "B.Paste")
			(net "M_H_DQ<33>")
		)
		(pad "243" smd rect
			(at -4.59994 88.399874 270)
			(size 1.8034 0.508)
			(layers "B.Cu" "B.Mask" "B.Paste")
			(net "GND")
		)
		(pad "244" smd rect
			(at -4.59994 89.250012 270)
			(size 1.8034 0.508)
			(layers "B.Cu" "B.Mask" "B.Paste")
			(net "M_H_DQS_DN<4>")
		)
		(pad "245" smd rect
			(at -4.59994 90.099896 270)
			(size 1.8034 0.508)
			(layers "B.Cu" "B.Mask" "B.Paste")
			(net "M_H_DQS_DP<4>")
		)
		(pad "246" smd rect
			(at -4.59994 90.950034 270)
			(size 1.8034 0.508)
			(layers "B.Cu" "B.Mask" "B.Paste")
			(net "GND")
		)
		(pad "247" smd rect
			(at -4.59994 91.799918 270)
			(size 1.8034 0.508)
			(layers "B.Cu" "B.Mask" "B.Paste")
			(net "M_H_DQ<39>")
		)
		(pad "248" smd rect
			(at -4.59994 92.650056 270)
			(size 1.8034 0.508)
			(layers "B.Cu" "B.Mask" "B.Paste")
			(net "GND")
		)
		(pad "249" smd rect
			(at -4.59994 93.49994 270)
			(size 1.8034 0.508)
			(layers "B.Cu" "B.Mask" "B.Paste")
			(net "M_H_DQ<35>")
		)
		(pad "250" smd rect
			(at -4.59994 94.350078 270)
			(size 1.8034 0.508)
			(layers "B.Cu" "B.Mask" "B.Paste")
			(net "GND")
		)
		(pad "251" smd rect
			(at -4.59994 95.199962 270)
			(size 1.8034 0.508)
			(layers "B.Cu" "B.Mask" "B.Paste")
			(net "M_H_DQ<45>")
		)
		(pad "252" smd rect
			(at -4.59994 96.0501 270)
			(size 1.8034 0.508)
			(layers "B.Cu" "B.Mask" "B.Paste")
			(net "GND")
		)
		(pad "253" smd rect
			(at -4.59994 96.899984 270)
			(size 1.8034 0.508)
			(layers "B.Cu" "B.Mask" "B.Paste")
			(net "M_H_DQ<41>")
		)
		(pad "254" smd rect
			(at -4.59994 97.750122 270)
			(size 1.8034 0.508)
			(layers "B.Cu" "B.Mask" "B.Paste")
			(net "GND")
		)
		(pad "255" smd rect
			(at -4.59994 98.600006 270)
			(size 1.8034 0.508)
			(layers "B.Cu" "B.Mask" "B.Paste")
			(net "M_H_DQS_DN<5>")
		)
		(pad "256" smd rect
			(at -4.59994 99.44989 270)
			(size 1.8034 0.508)
			(layers "B.Cu" "B.Mask" "B.Paste")
			(net "M_H_DQS_DP<5>")
		)
		(pad "257" smd rect
			(at -4.59994 100.300028 270)
			(size 1.8034 0.508)
			(layers "B.Cu" "B.Mask" "B.Paste")
			(net "GND")
		)
		(pad "258" smd rect
			(at -4.59994 101.149912 270)
			(size 1.8034 0.508)
			(layers "B.Cu" "B.Mask" "B.Paste")
			(net "M_H_DQ<47>")
		)
		(pad "259" smd rect
			(at -4.59994 102.00005 270)
			(size 1.8034 0.508)
			(layers "B.Cu" "B.Mask" "B.Paste")
			(net "GND")
		)
		(pad "260" smd rect
			(at -4.59994 102.849934 270)
			(size 1.8034 0.508)
			(layers "B.Cu" "B.Mask" "B.Paste")
			(net "M_H_DQ<43>")
		)
		(pad "261" smd rect
			(at -4.59994 103.700072 270)
			(size 1.8034 0.508)
			(layers "B.Cu" "B.Mask" "B.Paste")
			(net "GND")
		)
		(pad "262" smd rect
			(at -4.59994 104.549956 270)
			(size 1.8034 0.508)
			(layers "B.Cu" "B.Mask" "B.Paste")
			(net "M_H_DQ<53>")
		)
		(pad "263" smd rect
			(at -4.59994 105.400094 270)
			(size 1.8034 0.508)
			(layers "B.Cu" "B.Mask" "B.Paste")
			(net "GND")
		)
		(pad "264" smd rect
			(at -4.59994 106.249978 270)
			(size 1.8034 0.508)
			(layers "B.Cu" "B.Mask" "B.Paste")
			(net "M_H_DQ<49>")
		)
		(pad "265" smd rect
			(at -4.59994 107.100116 270)
			(size 1.8034 0.508)
			(layers "B.Cu" "B.Mask" "B.Paste")
			(net "GND")
		)
		(pad "266" smd rect
			(at -4.59994 107.95 270)
			(size 1.8034 0.508)
			(layers "B.Cu" "B.Mask" "B.Paste")
			(net "M_H_DQS_DN<6>")
		)
		(pad "267" smd rect
			(at -4.59994 108.799884 270)
			(size 1.8034 0.508)
			(layers "B.Cu" "B.Mask" "B.Paste")
			(net "M_H_DQS_DP<6>")
		)
		(pad "268" smd rect
			(at -4.59994 109.650022 270)
			(size 1.8034 0.508)
			(layers "B.Cu" "B.Mask" "B.Paste")
			(net "GND")
		)
		(pad "269" smd rect
			(at -4.59994 110.499906 270)
			(size 1.8034 0.508)
			(layers "B.Cu" "B.Mask" "B.Paste")
			(net "M_H_DQ<55>")
		)
		(pad "270" smd rect
			(at -4.59994 111.350044 270)
			(size 1.8034 0.508)
			(layers "B.Cu" "B.Mask" "B.Paste")
			(net "GND")
		)
		(pad "271" smd rect
			(at -4.59994 112.199928 270)
			(size 1.8034 0.508)
			(layers "B.Cu" "B.Mask" "B.Paste")
			(net "M_H_DQ<51>")
		)
		(pad "272" smd rect
			(at -4.59994 113.050066 270)
			(size 1.8034 0.508)
			(layers "B.Cu" "B.Mask" "B.Paste")
			(net "GND")
		)
		(pad "273" smd rect
			(at -4.59994 113.89995 270)
			(size 1.8034 0.508)
			(layers "B.Cu" "B.Mask" "B.Paste")
			(net "M_H_DQ<61>")
		)
		(pad "274" smd rect
			(at -4.59994 114.750088 270)
			(size 1.8034 0.508)
			(layers "B.Cu" "B.Mask" "B.Paste")
			(net "GND")
		)
		(pad "275" smd rect
			(at -4.59994 115.599972 270)
			(size 1.8034 0.508)
			(layers "B.Cu" "B.Mask" "B.Paste")
			(net "M_H_DQ<57>")
		)
		(pad "276" smd rect
			(at -4.59994 116.45011 270)
			(size 1.8034 0.508)
			(layers "B.Cu" "B.Mask" "B.Paste")
			(net "GND")
		)
		(pad "277" smd rect
			(at -4.59994 117.299994 270)
			(size 1.8034 0.508)
			(layers "B.Cu" "B.Mask" "B.Paste")
			(net "M_H_DQS_DN<7>")
		)
		(pad "278" smd rect
			(at -4.59994 118.149878 270)
			(size 1.8034 0.508)
			(layers "B.Cu" "B.Mask" "B.Paste")
			(net "M_H_DQS_DP<7>")
		)
		(pad "279" smd rect
			(at -4.59994 119.000016 270)
			(size 1.8034 0.508)
			(layers "B.Cu" "B.Mask" "B.Paste")
			(net "GND")
		)
		(pad "280" smd rect
			(at -4.59994 119.8499 270)
			(size 1.8034 0.508)
			(layers "B.Cu" "B.Mask" "B.Paste")
			(net "M_H_DQ<63>")
		)
		(pad "281" smd rect
			(at -4.59994 120.700038 270)
			(size 1.8034 0.508)
			(layers "B.Cu" "B.Mask" "B.Paste")
			(net "GND")
		)
		(pad "282" smd rect
			(at -4.59994 121.549922 270)
			(size 1.8034 0.508)
			(layers "B.Cu" "B.Mask" "B.Paste")
			(net "M_H_DQ<59>")
		)
		(pad "283" smd rect
			(at -4.59994 122.40006 270)
			(size 1.8034 0.508)
			(layers "B.Cu" "B.Mask" "B.Paste")
			(net "GND")
		)
		(pad "284" smd rect
			(at -4.59994 123.249944 270)
			(size 1.8034 0.508)
			(layers "B.Cu" "B.Mask" "B.Paste")
			(net "PVPP_GHJ")
		)
		(pad "285" smd rect
			(at -4.59994 124.100082 270)
			(size 1.8034 0.508)
			(layers "B.Cu" "B.Mask" "B.Paste")
			(net "SMB_DDR_GHJ_VPP_SDA")
		)
		(pad "286" smd rect
			(at -4.59994 124.949966 270)
			(size 1.8034 0.508)
			(layers "B.Cu" "B.Mask" "B.Paste")
			(net "PVPP_GHJ")
		)
		(pad "287" smd rect
			(at -4.59994 125.800104 270)
			(size 1.8034 0.508)
			(layers "B.Cu" "B.Mask" "B.Paste")
			(net "PVPP_GHJ")
		)
		(pad "288" smd rect
			(at -4.59994 126.649988 270)
			(size 1.8034 0.508)
			(layers "B.Cu" "B.Mask" "B.Paste")
			(net "PVPP_GHJ")
		)
	)
)
